(kicad_pcb
	(version 20241229)
	(generator "pcbnew")
	(generator_version "9.0")
	(general
		(thickness 1.294)
		(legacy_teardrops no)
	)
	(paper "A3")
	(title_block
		(title "Kintex 410T devboard")
		(date "2024-04-03")
		(rev "1.1.2")
		(comment 9 "footprints 156-160 of 975")
	)
	(layers
		(0 "F.Cu" mixed)
		(4 "In1.Cu" power)
		(6 "In2.Cu" power)
		(8 "In3.Cu" mixed)
		(10 "In4.Cu" power)
		(12 "In5.Cu" mixed)
		(14 "In6.Cu" power)
		(16 "In7.Cu" mixed)
		(18 "In8.Cu" power)
		(2 "B.Cu" mixed)
		(9 "F.Adhes" user "F.Adhesive")
		(11 "B.Adhes" user "B.Adhesive")
		(13 "F.Paste" user)
		(15 "B.Paste" user)
		(5 "F.SilkS" user "F.Silkscreen")
		(7 "B.SilkS" user "B.Silkscreen")
		(1 "F.Mask" user)
		(3 "B.Mask" user)
		(17 "Dwgs.User" user "User.Drawings")
		(19 "Cmts.User" user "User.Comments")
		(21 "Eco1.User" user "User.Eco1")
		(23 "Eco2.User" user "User.Eco2")
		(25 "Edge.Cuts" user)
		(27 "Margin" user)
		(31 "F.CrtYd" user "F.Courtyard")
		(29 "B.CrtYd" user "B.Courtyard")
		(35 "F.Fab" user)
		(33 "B.Fab" user)
	)
	(footprint "antmicro-footprints:C_0402_1005Metric"
		(layer "F.Cu")
		(at 153.1 139.2 180)
		(descr "Capacitor SMD 0402")
		(tags "capacitor SMD 0402")
		(property "Reference" "C353"
			(at -1.85 2.2 225)
			(layer "F.SilkS")
			(effects
				(font
					(size 0.7 0.7)
					(thickness 0.15)
				)
				(justify right bottom)
			)
		)
		(property "Value" "C_10u_0402"
			(at 0 1.4 0)
			(layer "F.Fab")
			(effects
				(font
					(size 0.7 0.7)
					(thickness 0.15)
				)
				(justify right bottom)
			)
		)
		(property "Description" "SMD Multilayer Ceramic Capacitor, 10 µF, 6.3 V, 0402 [1005 Metric], ± 20%, X5R, CC Series"
			(at 0 0 180)
			(layer "F.Fab")
			(hide yes)
			(effects
				(font
					(size 1.27 1.27)
					(thickness 0.15)
				)
			)
		)
		(property "Author" "Antmicro"
			(at 306.2 278.4 0)
			(layer "F.Fab")
			(hide yes)
			(effects
				(font
					(size 1 1)
					(thickness 0.15)
				)
			)
		)
		(property "Dielectric" ""
			(at 306.2 278.4 0)
			(layer "F.Fab")
			(hide yes)
			(effects
				(font
					(size 1 1)
					(thickness 0.15)
				)
			)
		)
		(property "License" "Apache-2.0"
			(at 306.2 278.4 0)
			(layer "F.Fab")
			(hide yes)
			(effects
				(font
					(size 1 1)
					(thickness 0.15)
				)
			)
		)
		(property "MPN" "CC0402MRX5R5BB106"
			(at 306.2 278.4 0)
			(layer "F.Fab")
			(hide yes)
			(effects
				(font
					(size 1 1)
					(thickness 0.15)
				)
			)
		)
		(property "Manufacturer" "YAGEO"
			(at 306.2 278.4 0)
			(layer "F.Fab")
			(hide yes)
			(effects
				(font
					(size 1 1)
					(thickness 0.15)
				)
			)
		)
		(property "Val" "10u"
			(at 306.2 278.4 0)
			(layer "F.Fab")
			(hide yes)
			(effects
				(font
					(size 1 1)
					(thickness 0.15)
				)
			)
		)
		(property "Voltage" ""
			(at 306.2 278.4 0)
			(layer "F.Fab")
			(hide yes)
			(effects
				(font
					(size 1 1)
					(thickness 0.15)
				)
			)
		)
		(sheetname "DC-DC Converters")
		(sheetfile "dc-dc.kicad_sch")
		(attr smd)
		(fp_rect
			(start -0.925 -0.47)
			(end 0.925 0.47)
			(stroke
				(width 0.05)
				(type default)
			)
			(fill no)
			(layer "F.CrtYd")
		)
		(fp_line
			(start 0.504 0.248)
			(end -0.494 0.248)
			(stroke
				(width 0.15)
				(type solid)
			)
			(layer "F.Fab")
		)
		(fp_line
			(start 0.504 -0.25)
			(end 0.504 0.248)
			(stroke
				(width 0.15)
				(type solid)
			)
			(layer "F.Fab")
		)
		(fp_line
			(start -0.494 0.248)
			(end -0.494 -0.25)
			(stroke
				(width 0.15)
				(type solid)
			)
			(layer "F.Fab")
		)
		(fp_line
			(start -0.494 -0.25)
			(end 0.504 -0.25)
			(stroke
				(width 0.15)
				(type solid)
			)
			(layer "F.Fab")
		)
		(pad "1" smd roundrect
			(at -0.48 0 180)
			(size 0.59 0.64)
			(layers "F.Cu" "F.Mask" "F.Paste")
			(roundrect_rratio 0.25)
			(net 1 "GND")
			(pintype "passive")
		)
		(pad "2" smd roundrect
			(at 0.48 0 180)
			(size 0.59 0.64)
			(layers "F.Cu" "F.Mask" "F.Paste")
			(roundrect_rratio 0.25)
			(net 748 "/DC-DC Converters/MGTAVTT_OUT")
			(pintype "passive")
		)
	)
	(footprint "antmicro-footprints:NetTie-2_SMD_Pad0.127mm"
		(layer "F.Cu")
		(at 249.7 143.602 -90)
		(descr "Net tie, 2 pin, 0.127mm  SMD pads")
		(tags "net tie")
		(property "Reference" "NT20"
			(at -0.128 -1.345 270)
			(layer "F.SilkS")
			(hide yes)
			(effects
				(font
					(size 0.7 0.7)
					(thickness 0.15)
				)
				(justify left bottom)
			)
		)
		(property "Value" "Net-Tie_2"
			(at 0 1.199 270)
			(layer "F.Fab")
			(effects
				(font
					(size 0.7 0.7)
					(thickness 0.15)
				)
				(justify left bottom)
			)
		)
		(property "Description" "Net tie, 2 pins"
			(at 0 0 270)
			(layer "F.Fab")
			(hide yes)
			(effects
				(font
					(size 1.27 1.27)
					(thickness 0.15)
				)
			)
		)
		(property "Author" "Antmicro"
			(at 106.098 393.302 0)
			(layer "F.Fab")
			(hide yes)
			(effects
				(font
					(size 1 1)
					(thickness 0.15)
				)
			)
		)
		(property "License" "Apache-2.0"
			(at 106.098 393.302 0)
			(layer "F.Fab")
			(hide yes)
			(effects
				(font
					(size 1 1)
					(thickness 0.15)
				)
			)
		)
		(property "MPN" ""
			(at 106.098 393.302 0)
			(layer "F.Fab")
			(hide yes)
			(effects
				(font
					(size 1 1)
					(thickness 0.15)
				)
			)
		)
		(property "Manufacturer" ""
			(at 106.098 393.302 0)
			(layer "F.Fab")
			(hide yes)
			(effects
				(font
					(size 1 1)
					(thickness 0.15)
				)
			)
		)
		(sheetname "FPGA Bank 14 & 15")
		(sheetfile "fpga-bank-14-15.kicad_sch")
		(attr exclude_from_pos_files)
		(net_tie_pad_groups "1, 2")
		(fp_poly
			(pts
				(xy -0.0635 -0.0635) (xy 0.0625 -0.0635) (xy 0.0625 0.0635) (xy -0.0635 0.0635)
			)
			(stroke
				(width 0)
				(type solid)
			)
			(fill yes)
			(layer "F.Cu")
		)
		(pad "1" smd roundrect
			(at -0.127 0 90)
			(size 0.127 0.127)
			(layers "F.Cu")
			(roundrect_rratio 0.5)
			(chamfer_ratio 0)
			(chamfer top_left bottom_left)
			(net 75 "/FPGA Bank 14 & 15/SYSTEM_FLASH.~{CS}")
			(pinfunction "1")
			(pintype "passive")
		)
		(pad "2" smd roundrect
			(at 0.126 0 270)
			(size 0.127 0.127)
			(layers "F.Cu")
			(roundrect_rratio 0.5)
			(chamfer_ratio 0)
			(chamfer top_left bottom_left)
			(net 1334 "/SUP_MCU.CFG_CS")
			(pinfunction "2")
			(pintype "passive")
		)
	)
	(footprint "antmicro-footprints:R_0402_1005Metric"
		(layer "F.Cu")
		(at 246.999 113.904 180)
		(descr "Resistor SMD 0402")
		(tags "resistor SMD 0402")
		(property "Reference" "R348"
			(at 1.449 1.654 0)
			(layer "F.SilkS")
			(effects
				(font
					(size 0.7 0.7)
					(thickness 0.15)
				)
				(justify left bottom)
			)
		)
		(property "Value" "R_10k_0402"
			(at 0 1.4 180)
			(layer "F.Fab")
			(effects
				(font
					(size 0.7 0.7)
					(thickness 0.15)
				)
				(justify left bottom)
			)
		)
		(property "Description" "SMD Chip Resistor, 10 kohm, ± 1%, 62.5 mW, 0402 [1005 Metric], Thick Film, General Purpose"
			(at 0 0 180)
			(layer "F.Fab")
			(hide yes)
			(effects
				(font
					(size 1.27 1.27)
					(thickness 0.15)
				)
			)
		)
		(property "Author" "Antmicro"
			(at 493.998 227.808 0)
			(layer "F.Fab")
			(hide yes)
			(effects
				(font
					(size 1 1)
					(thickness 0.15)
				)
			)
		)
		(property "License" "Apache-2.0"
			(at 493.998 227.808 0)
			(layer "F.Fab")
			(hide yes)
			(effects
				(font
					(size 1 1)
					(thickness 0.15)
				)
			)
		)
		(property "MPN" "CR0402-FX-1002GLF"
			(at 493.998 227.808 0)
			(layer "F.Fab")
			(hide yes)
			(effects
				(font
					(size 1 1)
					(thickness 0.15)
				)
			)
		)
		(property "Manufacturer" "Bourns"
			(at 493.998 227.808 0)
			(layer "F.Fab")
			(hide yes)
			(effects
				(font
					(size 1 1)
					(thickness 0.15)
				)
			)
		)
		(property "Tolerance" "1%"
			(at 493.998 227.808 0)
			(layer "F.Fab")
			(hide yes)
			(effects
				(font
					(size 1 1)
					(thickness 0.15)
				)
			)
		)
		(property "Val" "10k"
			(at 493.998 227.808 0)
			(layer "F.Fab")
			(hide yes)
			(effects
				(font
					(size 1 1)
					(thickness 0.15)
				)
			)
		)
		(sheetname "USB PHY")
		(sheetfile "usb-phy.kicad_sch")
		(attr smd)
		(fp_rect
			(start -0.925 -0.47)
			(end 0.925 0.47)
			(stroke
				(width 0.05)
				(type default)
			)
			(fill no)
			(layer "F.CrtYd")
		)
		(fp_rect
			(start -0.5 -0.25)
			(end 0.5 0.25)
			(stroke
				(width 0.15)
				(type solid)
			)
			(fill no)
			(layer "F.Fab")
		)
		(pad "1" smd roundrect
			(at -0.48 0 180)
			(size 0.59 0.64)
			(layers "F.Cu" "F.Mask" "F.Paste")
			(roundrect_rratio 0.25)
			(net 386 "Net-(U43-FLG)")
			(pintype "passive")
		)
		(pad "2" smd roundrect
			(at 0.48 0 180)
			(size 0.59 0.64)
			(layers "F.Cu" "F.Mask" "F.Paste")
			(roundrect_rratio 0.25)
			(net 703 "+5V")
			(pintype "passive")
		)
	)
	(footprint "antmicro-footprints:DFN3538"
		(layer "F.Cu")
		(at 244.7 174.5 180)
		(property "Reference" "D7"
			(at 0.7 -3.3 0)
			(unlocked yes)
			(layer "F.SilkS")
			(effects
				(font
					(size 0.7 0.7)
					(thickness 0.15)
				)
				(justify left bottom)
			)
		)
		(property "Value" "CD-MMBL110S"
			(at 0 3.5 180)
			(unlocked yes)
			(layer "F.Fab")
			(effects
				(font
					(size 0.7 0.7)
					(thickness 0.15)
				)
				(justify left bottom)
			)
		)
		(property "Description" "TVS diode"
			(at 0 0 180)
			(layer "F.Fab")
			(hide yes)
			(effects
				(font
					(size 1.27 1.27)
					(thickness 0.15)
				)
			)
		)
		(property "Author" "Antmicro"
			(at 489.4 349 0)
			(layer "F.Fab")
			(hide yes)
			(effects
				(font
					(size 1 1)
					(thickness 0.15)
				)
			)
		)
		(property "DNP" "DNP"
			(at 489.4 349 0)
			(layer "F.Fab")
			(hide yes)
			(effects
				(font
					(size 1 1)
					(thickness 0.15)
				)
			)
		)
		(property "License" "Apache-2.0"
			(at 489.4 349 0)
			(layer "F.Fab")
			(hide yes)
			(effects
				(font
					(size 1 1)
					(thickness 0.15)
				)
			)
		)
		(property "MPN" "CD-MMBL110S"
			(at 489.4 349 0)
			(layer "F.Fab")
			(hide yes)
			(effects
				(font
					(size 1 1)
					(thickness 0.15)
				)
			)
		)
		(property "Manufacturer" "Bourns"
			(at 489.4 349 0)
			(layer "F.Fab")
			(hide yes)
			(effects
				(font
					(size 1 1)
					(thickness 0.15)
				)
			)
		)
		(property "dnp" ""
			(at 489.4 349 0)
			(layer "F.Fab")
			(hide yes)
			(effects
				(font
					(size 1 1)
					(thickness 0.15)
				)
			)
		)
		(property "exclude_from_bom" ""
			(at 489.4 349 0)
			(layer "F.Fab")
			(hide yes)
			(effects
				(font
					(size 1 1)
					(thickness 0.15)
				)
			)
		)
		(sheetname "Power supply")
		(sheetfile "power-supply.kicad_sch")
		(attr smd exclude_from_bom)
		(fp_line
			(start 1.8 -2)
			(end 1.8 2.05)
			(stroke
				(width 0.15)
				(type solid)
			)
			(layer "F.SilkS")
		)
		(fp_line
			(start 1.6 2.05)
			(end 1.8 2.05)
			(stroke
				(width 0.15)
				(type solid)
			)
			(layer "F.SilkS")
		)
		(fp_line
			(start 1.6 -2)
			(end 1.8 -2)
			(stroke
				(width 0.15)
				(type solid)
			)
			(layer "F.SilkS")
		)
		(fp_line
			(start 0.9 -2.301)
			(end 0.598 -2.301)
			(stroke
				(width 0.15)
				(type solid)
			)
			(layer "F.SilkS")
		)
		(fp_line
			(start 0.748 -2.452)
			(end 0.748 -2.15)
			(stroke
				(width 0.15)
				(type solid)
			)
			(layer "F.SilkS")
		)
		(fp_line
			(start -0.902 -2.25)
			(end -0.6 -2.25)
			(stroke
				(width 0.15)
				(type solid)
			)
			(layer "F.SilkS")
		)
		(fp_line
			(start -0.95 2.05)
			(end 0.95 2.05)
			(stroke
				(width 0.15)
				(type solid)
			)
			(layer "F.SilkS")
		)
		(fp_line
			(start -0.95 -2)
			(end 0.95 -2)
			(stroke
				(width 0.15)
				(type solid)
			)
			(layer "F.SilkS")
		)
		(fp_line
			(start -1.8 2.05)
			(end -1.6 2.05)
			(stroke
				(width 0.15)
				(type solid)
			)
			(layer "F.SilkS")
		)
		(fp_line
			(start -1.8 -1.5)
			(end -1.8 2.05)
			(stroke
				(width 0.15)
				(type solid)
			)
			(layer "F.SilkS")
		)
		(fp_rect
			(start -2.1 -2.6)
			(end 2.1 2.6)
			(stroke
				(width 0.05)
				(type solid)
			)
			(fill no)
			(layer "F.CrtYd")
		)
		(fp_line
			(start -1.051 -2)
			(end -1.801 -1.25)
			(stroke
				(width 0.15)
				(type solid)
			)
			(layer "F.Fab")
		)
		(fp_rect
			(start 1.8 2.048)
			(end -1.8 -2)
			(stroke
				(width 0.15)
				(type solid)
			)
			(fill no)
			(layer "F.Fab")
		)
		(fp_text user "~"
			(at -0.31 2.59 180)
			(unlocked yes)
			(layer "F.SilkS")
			(effects
				(font
					(size 0.7 0.7)
					(thickness 0.15)
				)
				(justify left bottom)
			)
		)
		(pad "1" smd roundrect
			(at -1.27 -1.85 270)
			(size 1.4 0.48)
			(layers "F.Cu" "F.Mask" "F.Paste")
			(roundrect_rratio 0.25)
			(net 762 "Net-(D6-Pad1)")
			(pinfunction "1")
			(pintype "output")
		)
		(pad "2" smd roundrect
			(at 1.27 -1.85 270)
			(size 1.4 0.48)
			(layers "F.Cu" "F.Mask" "F.Paste")
			(roundrect_rratio 0.25)
			(net 763 "Net-(D6-Pad2)")
			(pinfunction "2")
			(pintype "output")
		)
		(pad "3" smd roundrect
			(at -1.27 1.85 270)
			(size 1.4 0.48)
			(layers "F.Cu" "F.Mask" "F.Paste")
			(roundrect_rratio 0.25)
			(net 766 "/HDMI + Ethernet/POE_ETH.VC3")
			(pinfunction "3")
			(pintype "input")
		)
		(pad "4" smd roundrect
			(at 1.27 1.85 270)
			(size 1.4 0.48)
			(layers "F.Cu" "F.Mask" "F.Paste")
			(roundrect_rratio 0.25)
			(net 767 "/HDMI + Ethernet/POE_ETH.VC4")
			(pinfunction "4")
			(pintype "input")
		)
	)
	(footprint "antmicro-footprints:LED_0603_1608Metric_G"
		(layer "F.Cu")
		(at 261.5 95.8)
		(descr "LED SMD 0603 Green")
		(tags "LED SMD 0603 Green")
		(property "Reference" "D23"
			(at -1 1.55 0)
			(layer "F.SilkS")
			(effects
				(font
					(size 0.7 0.7)
					(thickness 0.15)
				)
				(justify left bottom)
			)
		)
		(property "Value" "LED_G_0603_KP-1608CGCK"
			(at 0 1.6 0)
			(layer "F.Fab")
			(effects
				(font
					(size 0.7 0.7)
					(thickness 0.15)
				)
				(justify left bottom)
			)
		)
		(property "Description" "LED, Green, SMD, 0603, 20 mA, 2.1 V, 570 nm"
			(at 0 0 0)
			(layer "F.Fab")
			(hide yes)
			(effects
				(font
					(size 1.27 1.27)
					(thickness 0.15)
				)
			)
		)
		(property "Author" "Antmicro"
			(at 0 0 0)
			(layer "F.Fab")
			(hide yes)
			(effects
				(font
					(size 1 1)
					(thickness 0.15)
				)
			)
		)
		(property "Color" "Green"
			(at 0 0 0)
			(layer "F.Fab")
			(hide yes)
			(effects
				(font
					(size 1 1)
					(thickness 0.15)
				)
			)
		)
		(property "License" "Apache-2.0"
			(at 0 0 0)
			(layer "F.Fab")
			(hide yes)
			(effects
				(font
					(size 1 1)
					(thickness 0.15)
				)
			)
		)
		(property "MPN" "KP-1608CGCK"
			(at 0 0 0)
			(layer "F.Fab")
			(hide yes)
			(effects
				(font
					(size 1 1)
					(thickness 0.15)
				)
			)
		)
		(property "Manufacturer" "Kingbright"
			(at 0 0 0)
			(layer "F.Fab")
			(hide yes)
			(effects
				(font
					(size 1 1)
					(thickness 0.15)
				)
			)
		)
		(sheetname "User GPIO + LED + button + DIP switch")
		(sheetfile "user-gpio.kicad_sch")
		(attr smd)
		(fp_line
			(start -1.18 -0.319)
			(end -1.18 0.321)
			(stroke
				(width 0.15)
				(type solid)
			)
			(layer "F.SilkS")
		)
		(fp_line
			(start -0.094672 0.001008)
			(end -0.24 0.001008)
			(stroke
				(width 0.1)
				(type solid)
			)
			(layer "F.SilkS")
		)
		(fp_line
			(start -0.094672 0.001008)
			(end 0.105328 -0.198992)
			(stroke
				(width 0.1)
				(type solid)
			)
			(layer "F.SilkS")
		)
		(fp_line
			(start -0.094672 0.201008)
			(end -0.094672 -0.198992)
			(stroke
				(width 0.1)
				(type solid)
			)
			(layer "F.SilkS")
		)
		(fp_line
			(start 0.105328 0.001008)
			(end 0.24 0.001)
			(stroke
				(width 0.1)
				(type solid)
			)
			(layer "F.SilkS")
		)
		(fp_line
			(start 0.105328 0.201008)
			(end -0.094672 0.001008)
			(stroke
				(width 0.1)
				(type solid)
			)
			(layer "F.SilkS")
		)
		(fp_line
			(start 0.105328 0.201008)
			(end 0.105328 -0.198992)
			(stroke
				(width 0.1)
				(type solid)
			)
			(layer "F.SilkS")
		)
		(fp_line
			(start 0.22 -0.35)
			(end -0.22 -0.35)
			(stroke
				(width 0.15)
				(type solid)
			)
			(layer "F.SilkS")
		)
		(fp_line
			(start 0.22 0.35)
			(end -0.22 0.35)
			(stroke
				(width 0.15)
				(type solid)
			)
			(layer "F.SilkS")
		)
		(fp_rect
			(start 1.25 0.65)
			(end -1.25 -0.65)
			(stroke
				(width 0.05)
				(type solid)
			)
			(fill no)
			(layer "F.CrtYd")
		)
		(fp_line
			(start -0.199 -0.202)
			(end -0.199 0.1)
			(stroke
				(width 0.15)
				(type solid)
			)
			(layer "F.Fab")
		)
		(fp_line
			(start -0.199 0)
			(end -0.597 0)
			(stroke
				(width 0.15)
				(type solid)
			)
			(layer "F.Fab")
		)
		(fp_line
			(start -0.199 0.2)
			(end -0.199 0.1)
			(stroke
				(width 0.15)
				(type solid)
			)
			(layer "F.Fab")
		)
		(fp_line
			(start -0.101 0)
			(end 0.201 0.2)
			(stroke
				(width 0.15)
				(type solid)
			)
			(layer "F.Fab")
		)
		(fp_line
			(start 0.201 -0.202)
			(end -0.101 0)
			(stroke
				(width 0.15)
				(type solid)
			)
			(layer "F.Fab")
		)
		(fp_line
			(start 0.201 0)
			(end 0.201 -0.202)
			(stroke
				(width 0.15)
				(type solid)
			)
			(layer "F.Fab")
		)
		(fp_line
			(start 0.201 0.2)
			(end 0.201 0)
			(stroke
				(width 0.15)
				(type solid)
			)
			(layer "F.Fab")
		)
		(fp_line
			(start 0.599 0)
			(end 0.201 0)
			(stroke
				(width 0.15)
				(type solid)
			)
			(layer "F.Fab")
		)
		(fp_rect
			(start 0.848 0.4)
			(end -0.85 -0.402)
			(stroke
				(width 0.15)
				(type solid)
			)
			(fill no)
			(layer "F.Fab")
		)
		(pad "1" smd roundrect
			(at -0.7 0 180)
			(size 0.8 1)
			(layers "F.Cu" "F.Mask" "F.Paste")
			(roundrect_rratio 0.2)
			(net 768 "Net-(D23-C)")
			(pinfunction "C")
			(pintype "passive")
		)
		(pad "2" smd roundrect
			(at 0.7 0 180)
			(size 0.8 1)
			(layers "F.Cu" "F.Mask" "F.Paste")
			(roundrect_rratio 0.2)
			(net 785 "Net-(D23-A)")
			(pinfunction "A")
			(pintype "passive")
		)
	)
)
